(kicad_pcb
	(version 20260206)
	(generator "pcbnew")
	(generator_version "10.0")
	(general
		(thickness 1.6)
		(legacy_teardrops no)
	)
	(paper "A4")
	(title_block
		(title "01162023_DA0F0TEBIF0_F0T_Expander_BD_F_brd_V02_OCP.brd")
		(comment 1 "Grand Teton / footprints 6450-6456 of 9728")
	)
	(layers
		(0 "F.Cu" signal "TOP")
		(4 "In1.Cu" signal "GND")
		(6 "In2.Cu" signal "VCC")
		(8 "In3.Cu" signal "VCC1")
		(10 "In4.Cu" signal "GND1")
		(12 "In5.Cu" signal "IN1")
		(14 "In6.Cu" signal "GND2")
		(16 "In7.Cu" signal "IN2")
		(18 "In8.Cu" signal "GND3")
		(20 "In9.Cu" signal "IN3")
		(22 "In10.Cu" signal "GND4")
		(24 "In11.Cu" signal "IN4")
		(26 "In12.Cu" signal "GND5")
		(28 "In13.Cu" signal "IN5")
		(30 "In14.Cu" signal "GND6")
		(32 "In15.Cu" signal "IN6")
		(34 "In16.Cu" signal "GND7")
		(2 "B.Cu" signal "BOTTOM")
		(9 "F.Adhes" user "F.Adhesive")
		(11 "B.Adhes" user "B.Adhesive")
		(13 "F.Paste" user "Package Geometry/Pastemask Top")
		(15 "B.Paste" user "Package Geometry/Pastemask Bottom")
		(5 "F.SilkS" user "Ref Des/Silkscreen Top")
		(7 "B.SilkS" user "Ref Des/Silkscreen Bottom")
		(1 "F.Mask" user "Board Geometry/Soldermask Top")
		(3 "B.Mask" user "Board Geometry/Soldermask Bottom")
		(17 "Dwgs.User" user "User.Drawings")
		(19 "Cmts.User" user "User.Comments")
		(21 "Eco1.User" user "User.Eco1")
		(23 "Eco2.User" user "User.Eco2")
		(25 "Edge.Cuts" user "Board Geometry/Outline")
		(27 "Margin" user)
		(31 "F.CrtYd" user "Package Geometry/Place Bound Top")
		(29 "B.CrtYd" user "Package Geometry/Place Bound Bottom")
		(35 "F.Fab" user "Ref Des/Assembly Top")
		(33 "B.Fab" user "Ref Des/Assembly Bottom")
	)
	(footprint ""
		(layer "F.Cu")
		(at 379.633988 -4.836922)
		(property "Reference" "R5817"
			(at 0 0 0)
			(layer "F.SilkS")
			(hide yes)
			(effects
				(font
					(size 1.27 1.27)
				)
			)
		)
		(property "Value" ""
			(at 0 0 0)
			(layer "F.Fab")
			(effects
				(font
					(size 1.27 1.27)
				)
			)
		)
		(duplicate_pad_numbers_are_jumpers no)
		(fp_line
			(start -0.7874 -0.4064)
			(end 0.7874 -0.4064)
			(stroke
				(width 0.1524)
				(type default)
			)
			(layer "F.SilkS")
		)
		(fp_line
			(start -0.7874 0.4064)
			(end -0.7874 -0.4064)
			(stroke
				(width 0.1524)
				(type default)
			)
			(layer "F.SilkS")
		)
		(fp_line
			(start 0.7874 -0.4064)
			(end 0.7874 0.4064)
			(stroke
				(width 0.1524)
				(type default)
			)
			(layer "F.SilkS")
		)
		(fp_line
			(start 0.7874 0.4064)
			(end -0.7874 0.4064)
			(stroke
				(width 0.1524)
				(type default)
			)
			(layer "F.SilkS")
		)
		(fp_line
			(start -0.67945 -0.305054)
			(end -0.12065 -0.305054)
			(stroke
				(width 0.1)
				(type default)
			)
			(layer "F.Fab")
		)
		(fp_line
			(start -0.67945 0.3048)
			(end -0.67945 -0.305054)
			(stroke
				(width 0.1)
				(type default)
			)
			(layer "F.Fab")
		)
		(fp_line
			(start -0.12065 -0.305054)
			(end -0.12065 -0.2794)
			(stroke
				(width 0.1)
				(type default)
			)
			(layer "F.Fab")
		)
		(fp_line
			(start -0.12065 -0.2794)
			(end 0.12065 -0.2794)
			(stroke
				(width 0.1)
				(type default)
			)
			(layer "F.Fab")
		)
		(fp_line
			(start -0.12065 0.2794)
			(end -0.12065 0.3048)
			(stroke
				(width 0.1)
				(type default)
			)
			(layer "F.Fab")
		)
		(fp_line
			(start -0.12065 0.3048)
			(end -0.67945 0.3048)
			(stroke
				(width 0.1)
				(type default)
			)
			(layer "F.Fab")
		)
		(fp_line
			(start 0.120396 0.2794)
			(end -0.12065 0.2794)
			(stroke
				(width 0.1)
				(type default)
			)
			(layer "F.Fab")
		)
		(fp_line
			(start 0.120396 0.3048)
			(end 0.120396 0.2794)
			(stroke
				(width 0.1)
				(type default)
			)
			(layer "F.Fab")
		)
		(fp_line
			(start 0.12065 -0.3048)
			(end 0.67945 -0.3048)
			(stroke
				(width 0.1)
				(type default)
			)
			(layer "F.Fab")
		)
		(fp_line
			(start 0.12065 -0.2794)
			(end 0.12065 -0.3048)
			(stroke
				(width 0.1)
				(type default)
			)
			(layer "F.Fab")
		)
		(fp_line
			(start 0.67945 -0.3048)
			(end 0.67945 0.3048)
			(stroke
				(width 0.1)
				(type default)
			)
			(layer "F.Fab")
		)
		(fp_line
			(start 0.67945 0.3048)
			(end 0.120396 0.3048)
			(stroke
				(width 0.1)
				(type default)
			)
			(layer "F.Fab")
		)
		(pad "1" smd circle
			(at -0.40005 0)
			(size 0 0)
			(layers "F.Cu" "F.Mask" "F.Paste")
			(net "LM75_3_A2")
		)
		(pad "2" smd circle
			(at 0.40005 0)
			(size 0 0)
			(layers "F.Cu" "F.Mask" "F.Paste")
			(net "P3V3_AUX")
		)
	)
	(footprint ""
		(layer "F.Cu")
		(at 104.267762 -54.067456)
		(property "Reference" "PR221"
			(at 0 0 0)
			(layer "F.SilkS")
			(hide yes)
			(effects
				(font
					(size 1.27 1.27)
				)
			)
		)
		(property "Value" ""
			(at 0 0 0)
			(layer "F.Fab")
			(effects
				(font
					(size 1.27 1.27)
				)
			)
		)
		(duplicate_pad_numbers_are_jumpers no)
		(fp_line
			(start -0.7874 -0.4064)
			(end 0.7874 -0.4064)
			(stroke
				(width 0.1524)
				(type default)
			)
			(layer "F.SilkS")
		)
		(fp_line
			(start -0.7874 0.4064)
			(end -0.7874 -0.4064)
			(stroke
				(width 0.1524)
				(type default)
			)
			(layer "F.SilkS")
		)
		(fp_line
			(start 0.7874 -0.4064)
			(end 0.7874 0.4064)
			(stroke
				(width 0.1524)
				(type default)
			)
			(layer "F.SilkS")
		)
		(fp_line
			(start 0.7874 0.4064)
			(end -0.7874 0.4064)
			(stroke
				(width 0.1524)
				(type default)
			)
			(layer "F.SilkS")
		)
		(fp_line
			(start -0.67945 -0.305054)
			(end -0.12065 -0.305054)
			(stroke
				(width 0.1)
				(type default)
			)
			(layer "F.Fab")
		)
		(fp_line
			(start -0.67945 0.3048)
			(end -0.67945 -0.305054)
			(stroke
				(width 0.1)
				(type default)
			)
			(layer "F.Fab")
		)
		(fp_line
			(start -0.12065 -0.305054)
			(end -0.12065 -0.2794)
			(stroke
				(width 0.1)
				(type default)
			)
			(layer "F.Fab")
		)
		(fp_line
			(start -0.12065 -0.2794)
			(end 0.12065 -0.2794)
			(stroke
				(width 0.1)
				(type default)
			)
			(layer "F.Fab")
		)
		(fp_line
			(start -0.12065 0.2794)
			(end -0.12065 0.3048)
			(stroke
				(width 0.1)
				(type default)
			)
			(layer "F.Fab")
		)
		(fp_line
			(start -0.12065 0.3048)
			(end -0.67945 0.3048)
			(stroke
				(width 0.1)
				(type default)
			)
			(layer "F.Fab")
		)
		(fp_line
			(start 0.120396 0.2794)
			(end -0.12065 0.2794)
			(stroke
				(width 0.1)
				(type default)
			)
			(layer "F.Fab")
		)
		(fp_line
			(start 0.120396 0.3048)
			(end 0.120396 0.2794)
			(stroke
				(width 0.1)
				(type default)
			)
			(layer "F.Fab")
		)
		(fp_line
			(start 0.12065 -0.3048)
			(end 0.67945 -0.3048)
			(stroke
				(width 0.1)
				(type default)
			)
			(layer "F.Fab")
		)
		(fp_line
			(start 0.12065 -0.2794)
			(end 0.12065 -0.3048)
			(stroke
				(width 0.1)
				(type default)
			)
			(layer "F.Fab")
		)
		(fp_line
			(start 0.67945 -0.3048)
			(end 0.67945 0.3048)
			(stroke
				(width 0.1)
				(type default)
			)
			(layer "F.Fab")
		)
		(fp_line
			(start 0.67945 0.3048)
			(end 0.120396 0.3048)
			(stroke
				(width 0.1)
				(type default)
			)
			(layer "F.Fab")
		)
		(pad "1" smd circle
			(at -0.40005 0)
			(size 0 0)
			(layers "F.Cu" "F.Mask" "F.Paste")
			(net "P12V_SSD3_OCP")
		)
		(pad "2" smd circle
			(at 0.40005 0)
			(size 0 0)
			(layers "F.Cu" "F.Mask" "F.Paste")
			(net "GND")
		)
	)
	(footprint ""
		(layer "F.Cu")
		(at 312.695082 -35.48253)
		(property "Reference" "U392"
			(at -2.559812 1.09093 90)
			(unlocked yes)
			(layer "F.SilkS")
			(effects
				(font
					(size 0.7874 0.5842)
					(thickness 0.1524)
				)
				(justify left)
			)
		)
		(property "Value" ""
			(at 0 0 0)
			(layer "F.Fab")
			(effects
				(font
					(size 1.27 1.27)
				)
			)
		)
		(duplicate_pad_numbers_are_jumpers no)
		(fp_line
			(start -1.3462 -1.1938)
			(end -1.3462 1.1684)
			(stroke
				(width 0.1524)
				(type default)
			)
			(layer "F.SilkS")
		)
		(fp_line
			(start -1.3462 1.1938)
			(end 1.3462 1.1938)
			(stroke
				(width 0.1524)
				(type default)
			)
			(layer "F.SilkS")
		)
		(fp_line
			(start 1.3462 -1.1938)
			(end -1.3462 -1.1938)
			(stroke
				(width 0.1524)
				(type default)
			)
			(layer "F.SilkS")
		)
		(fp_line
			(start 1.3462 1.1938)
			(end 1.3462 -1.1938)
			(stroke
				(width 0.1524)
				(type default)
			)
			(layer "F.SilkS")
		)
		(fp_poly
			(pts
				(xy -1.447038 -0.760476) (xy -2.052066 -0.457962) (xy -2.052066 -1.06299)
			)
			(stroke
				(width 0)
				(type default)
			)
			(fill yes)
			(layer "F.SilkS")
		)
		(fp_line
			(start -0.674878 -1.124966)
			(end -0.674878 1.124966)
			(stroke
				(width 0.1)
				(type default)
			)
			(layer "F.Fab")
		)
		(fp_line
			(start -0.674878 1.124966)
			(end 0.674878 1.124966)
			(stroke
				(width 0.1)
				(type default)
			)
			(layer "F.Fab")
		)
		(fp_line
			(start 0.674878 -1.124966)
			(end -0.674878 -1.124966)
			(stroke
				(width 0.1)
				(type default)
			)
			(layer "F.Fab")
		)
		(fp_line
			(start 0.674878 1.124966)
			(end 0.674878 -1.124966)
			(stroke
				(width 0.1)
				(type default)
			)
			(layer "F.Fab")
		)
		(fp_poly
			(pts
				(xy -1.447038 -0.760476) (xy -2.052066 -0.457962) (xy -2.052066 -1.06299)
			)
			(stroke
				(width 0)
				(type default)
			)
			(fill yes)
			(layer "F.Fab")
		)
		(pad "1" smd rect
			(at -0.899922 -0.750062)
			(size 0.6096 0.6096)
			(layers "F.Cu" "F.Mask" "F.Paste")
			(net "PWRGD_P3V3_SSD11_R")
		)
		(pad "2" smd rect
			(at -0.899922 0 90)
			(size 0.4064 0.6096)
			(layers "F.Cu" "F.Mask" "F.Paste")
			(net "RST_SMB_SSD11_N")
		)
		(pad "3" smd rect
			(at -0.899922 0.750062)
			(size 0.6096 0.6096)
			(layers "F.Cu" "F.Mask" "F.Paste")
			(net "GND")
		)
		(pad "4" smd rect
			(at 0.899922 0.750062)
			(size 0.6096 0.6096)
			(layers "F.Cu" "F.Mask" "F.Paste")
			(net "RST_SMB_SSD11_ISO_N")
		)
		(pad "5" smd rect
			(at 0.899922 -0.750062)
			(size 0.6096 0.6096)
			(layers "F.Cu" "F.Mask" "F.Paste")
			(net "P3V3_AUX")
		)
	)
	(footprint ""
		(layer "F.Cu")
		(at 72.947276 -20.35556)
		(property "Reference" "C3891"
			(at 0 0 0)
			(layer "F.SilkS")
			(hide yes)
			(effects
				(font
					(size 1.27 1.27)
				)
			)
		)
		(property "Value" ""
			(at 0 0 0)
			(layer "F.Fab")
			(effects
				(font
					(size 1.27 1.27)
				)
			)
		)
		(duplicate_pad_numbers_are_jumpers no)
		(fp_line
			(start -0.7874 -0.4064)
			(end 0.7874 -0.4064)
			(stroke
				(width 0.1524)
				(type default)
			)
			(layer "F.SilkS")
		)
		(fp_line
			(start -0.7874 0.4064)
			(end -0.7874 -0.4064)
			(stroke
				(width 0.1524)
				(type default)
			)
			(layer "F.SilkS")
		)
		(fp_line
			(start 0.7874 -0.4064)
			(end 0.7874 0.4064)
			(stroke
				(width 0.1524)
				(type default)
			)
			(layer "F.SilkS")
		)
		(fp_line
			(start 0.7874 0.4064)
			(end -0.7874 0.4064)
			(stroke
				(width 0.1524)
				(type default)
			)
			(layer "F.SilkS")
		)
		(fp_line
			(start -0.67945 -0.305054)
			(end -0.12065 -0.305054)
			(stroke
				(width 0.1)
				(type default)
			)
			(layer "F.Fab")
		)
		(fp_line
			(start -0.67945 0.3048)
			(end -0.67945 -0.305054)
			(stroke
				(width 0.1)
				(type default)
			)
			(layer "F.Fab")
		)
		(fp_line
			(start -0.12065 -0.305054)
			(end -0.12065 -0.2794)
			(stroke
				(width 0.1)
				(type default)
			)
			(layer "F.Fab")
		)
		(fp_line
			(start -0.12065 -0.2794)
			(end 0.12065 -0.2794)
			(stroke
				(width 0.1)
				(type default)
			)
			(layer "F.Fab")
		)
		(fp_line
			(start -0.12065 0.2794)
			(end -0.12065 0.3048)
			(stroke
				(width 0.1)
				(type default)
			)
			(layer "F.Fab")
		)
		(fp_line
			(start -0.12065 0.3048)
			(end -0.67945 0.3048)
			(stroke
				(width 0.1)
				(type default)
			)
			(layer "F.Fab")
		)
		(fp_line
			(start 0.120396 0.2794)
			(end -0.12065 0.2794)
			(stroke
				(width 0.1)
				(type default)
			)
			(layer "F.Fab")
		)
		(fp_line
			(start 0.120396 0.3048)
			(end 0.120396 0.2794)
			(stroke
				(width 0.1)
				(type default)
			)
			(layer "F.Fab")
		)
		(fp_line
			(start 0.12065 -0.3048)
			(end 0.67945 -0.3048)
			(stroke
				(width 0.1)
				(type default)
			)
			(layer "F.Fab")
		)
		(fp_line
			(start 0.12065 -0.2794)
			(end 0.12065 -0.3048)
			(stroke
				(width 0.1)
				(type default)
			)
			(layer "F.Fab")
		)
		(fp_line
			(start 0.67945 -0.3048)
			(end 0.67945 0.3048)
			(stroke
				(width 0.1)
				(type default)
			)
			(layer "F.Fab")
		)
		(fp_line
			(start 0.67945 0.3048)
			(end 0.120396 0.3048)
			(stroke
				(width 0.1)
				(type default)
			)
			(layer "F.Fab")
		)
		(pad "1" smd circle
			(at -0.40005 0)
			(size 0 0)
			(layers "F.Cu" "F.Mask" "F.Paste")
			(net "P12V_SSD2")
		)
		(pad "2" smd circle
			(at 0.40005 0)
			(size 0 0)
			(layers "F.Cu" "F.Mask" "F.Paste")
			(net "GND")
		)
	)
	(footprint ""
		(layer "F.Cu")
		(at 365.976916 -280.344118)
		(property "Reference" "PC202"
			(at 0 0 0)
			(layer "F.SilkS")
			(hide yes)
			(effects
				(font
					(size 1.27 1.27)
				)
			)
		)
		(property "Value" ""
			(at 0 0 0)
			(layer "F.Fab")
			(effects
				(font
					(size 1.27 1.27)
				)
			)
		)
		(duplicate_pad_numbers_are_jumpers no)
		(fp_line
			(start -0.7874 -0.4064)
			(end 0.7874 -0.4064)
			(stroke
				(width 0.1524)
				(type default)
			)
			(layer "F.SilkS")
		)
		(fp_line
			(start -0.7874 0.4064)
			(end -0.7874 -0.4064)
			(stroke
				(width 0.1524)
				(type default)
			)
			(layer "F.SilkS")
		)
		(fp_line
			(start 0.7874 -0.4064)
			(end 0.7874 0.4064)
			(stroke
				(width 0.1524)
				(type default)
			)
			(layer "F.SilkS")
		)
		(fp_line
			(start 0.7874 0.4064)
			(end -0.7874 0.4064)
			(stroke
				(width 0.1524)
				(type default)
			)
			(layer "F.SilkS")
		)
		(fp_line
			(start -0.67945 -0.305054)
			(end -0.12065 -0.305054)
			(stroke
				(width 0.1)
				(type default)
			)
			(layer "F.Fab")
		)
		(fp_line
			(start -0.67945 0.3048)
			(end -0.67945 -0.305054)
			(stroke
				(width 0.1)
				(type default)
			)
			(layer "F.Fab")
		)
		(fp_line
			(start -0.12065 -0.305054)
			(end -0.12065 -0.2794)
			(stroke
				(width 0.1)
				(type default)
			)
			(layer "F.Fab")
		)
		(fp_line
			(start -0.12065 -0.2794)
			(end 0.12065 -0.2794)
			(stroke
				(width 0.1)
				(type default)
			)
			(layer "F.Fab")
		)
		(fp_line
			(start -0.12065 0.2794)
			(end -0.12065 0.3048)
			(stroke
				(width 0.1)
				(type default)
			)
			(layer "F.Fab")
		)
		(fp_line
			(start -0.12065 0.3048)
			(end -0.67945 0.3048)
			(stroke
				(width 0.1)
				(type default)
			)
			(layer "F.Fab")
		)
		(fp_line
			(start 0.120396 0.2794)
			(end -0.12065 0.2794)
			(stroke
				(width 0.1)
				(type default)
			)
			(layer "F.Fab")
		)
		(fp_line
			(start 0.120396 0.3048)
			(end 0.120396 0.2794)
			(stroke
				(width 0.1)
				(type default)
			)
			(layer "F.Fab")
		)
		(fp_line
			(start 0.12065 -0.3048)
			(end 0.67945 -0.3048)
			(stroke
				(width 0.1)
				(type default)
			)
			(layer "F.Fab")
		)
		(fp_line
			(start 0.12065 -0.2794)
			(end 0.12065 -0.3048)
			(stroke
				(width 0.1)
				(type default)
			)
			(layer "F.Fab")
		)
		(fp_line
			(start 0.67945 -0.3048)
			(end 0.67945 0.3048)
			(stroke
				(width 0.1)
				(type default)
			)
			(layer "F.Fab")
		)
		(fp_line
			(start 0.67945 0.3048)
			(end 0.120396 0.3048)
			(stroke
				(width 0.1)
				(type default)
			)
			(layer "F.Fab")
		)
		(pad "1" smd circle
			(at -0.40005 0)
			(size 0 0)
			(layers "F.Cu" "F.Mask" "F.Paste")
			(net "P0V8_PEX2_VREF")
		)
		(pad "2" smd circle
			(at 0.40005 0)
			(size 0 0)
			(layers "F.Cu" "F.Mask" "F.Paste")
			(net "GND")
		)
	)
	(footprint ""
		(layer "F.Cu")
		(at 84.023962 -356.244906 90)
		(property "Reference" "C106"
			(at 0 0 90)
			(layer "F.SilkS")
			(hide yes)
			(effects
				(font
					(size 1.27 1.27)
				)
			)
		)
		(property "Value" ""
			(at 0 0 90)
			(layer "F.Fab")
			(effects
				(font
					(size 1.27 1.27)
				)
			)
		)
		(duplicate_pad_numbers_are_jumpers no)
		(fp_line
			(start 0.299974 -0.150114)
			(end 0.299974 0.150114)
			(stroke
				(width 0.1)
				(type default)
			)
			(layer "F.Fab")
		)
		(fp_line
			(start -0.299974 -0.150114)
			(end 0.299974 -0.150114)
			(stroke
				(width 0.1)
				(type default)
			)
			(layer "F.Fab")
		)
		(fp_line
			(start 0.299974 0.150114)
			(end -0.299974 0.150114)
			(stroke
				(width 0.1)
				(type default)
			)
			(layer "F.Fab")
		)
		(fp_line
			(start -0.299974 0.150114)
			(end -0.299974 -0.150114)
			(stroke
				(width 0.1)
				(type default)
			)
			(layer "F.Fab")
		)
		(pad "1" smd rect
			(at -0.2667 0 90)
			(size 0.3048 0.381)
			(layers "F.Cu" "F.Mask" "F.Paste")
			(net "P5E_PEX0_STN5_TX_DN<91>")
		)
		(pad "2" smd rect
			(at 0.2667 0 90)
			(size 0.3048 0.381)
			(layers "F.Cu" "F.Mask" "F.Paste")
			(net "P5E_PEX0_STN5_TX_C_DN<91>")
		)
	)
	(footprint ""
		(layer "F.Cu")
		(at 449.956428 -17.419574 180)
		(property "Reference" "R1733"
			(at 0 0 180)
			(layer "F.SilkS")
			(hide yes)
			(effects
				(font
					(size 1.27 1.27)
				)
			)
		)
		(property "Value" ""
			(at 0 0 180)
			(layer "F.Fab")
			(effects
				(font
					(size 1.27 1.27)
				)
			)
		)
		(duplicate_pad_numbers_are_jumpers no)
		(fp_line
			(start 0.7874 0.4064)
			(end -0.7874 0.4064)
			(stroke
				(width 0.1524)
				(type default)
			)
			(layer "F.SilkS")
		)
		(fp_line
			(start 0.7874 -0.4064)
			(end 0.7874 0.4064)
			(stroke
				(width 0.1524)
				(type default)
			)
			(layer "F.SilkS")
		)
		(fp_line
			(start -0.7874 0.4064)
			(end -0.7874 -0.4064)
			(stroke
				(width 0.1524)
				(type default)
			)
			(layer "F.SilkS")
		)
		(fp_line
			(start -0.7874 -0.4064)
			(end 0.7874 -0.4064)
			(stroke
				(width 0.1524)
				(type default)
			)
			(layer "F.SilkS")
		)
		(fp_line
			(start 0.67945 0.3048)
			(end 0.120396 0.3048)
			(stroke
				(width 0.1)
				(type default)
			)
			(layer "F.Fab")
		)
		(fp_line
			(start 0.67945 -0.3048)
			(end 0.67945 0.3048)
			(stroke
				(width 0.1)
				(type default)
			)
			(layer "F.Fab")
		)
		(fp_line
			(start 0.12065 -0.2794)
			(end 0.12065 -0.3048)
			(stroke
				(width 0.1)
				(type default)
			)
			(layer "F.Fab")
		)
		(fp_line
			(start 0.12065 -0.3048)
			(end 0.67945 -0.3048)
			(stroke
				(width 0.1)
				(type default)
			)
			(layer "F.Fab")
		)
		(fp_line
			(start 0.120396 0.3048)
			(end 0.120396 0.2794)
			(stroke
				(width 0.1)
				(type default)
			)
			(layer "F.Fab")
		)
		(fp_line
			(start 0.120396 0.2794)
			(end -0.12065 0.2794)
			(stroke
				(width 0.1)
				(type default)
			)
			(layer "F.Fab")
		)
		(fp_line
			(start -0.12065 0.3048)
			(end -0.67945 0.3048)
			(stroke
				(width 0.1)
				(type default)
			)
			(layer "F.Fab")
		)
		(fp_line
			(start -0.12065 0.2794)
			(end -0.12065 0.3048)
			(stroke
				(width 0.1)
				(type default)
			)
			(layer "F.Fab")
		)
		(fp_line
			(start -0.12065 -0.2794)
			(end 0.12065 -0.2794)
			(stroke
				(width 0.1)
				(type default)
			)
			(layer "F.Fab")
		)
		(fp_line
			(start -0.12065 -0.305054)
			(end -0.12065 -0.2794)
			(stroke
				(width 0.1)
				(type default)
			)
			(layer "F.Fab")
		)
		(fp_line
			(start -0.67945 0.3048)
			(end -0.67945 -0.305054)
			(stroke
				(width 0.1)
				(type default)
			)
			(layer "F.Fab")
		)
		(fp_line
			(start -0.67945 -0.305054)
			(end -0.12065 -0.305054)
			(stroke
				(width 0.1)
				(type default)
			)
			(layer "F.Fab")
		)
		(pad "1" smd circle
			(at -0.40005 0 180)
			(size 0 0)
			(layers "F.Cu" "F.Mask" "F.Paste")
			(net "P3V3_SSD15")
		)
		(pad "2" smd circle
			(at 0.40005 0 180)
			(size 0 0)
			(layers "F.Cu" "F.Mask" "F.Paste")
			(net "SMB_ISO_SSD15_SCL")
		)
	)
)
